FILE_TYPE = MULTI_PHYS_TABLE;

PART 'SCONN56_123276793'

{========================================================================================}
:VALUE                 | PART_TYPE | MATERIAL | PART_NUMBER    = STANDARD | LIFECYCLE          | PART_NUMBER   | JEDEC_TYPE                    | DESCRIPTION                               | MANUFTR | MANUF_PN      | RD_CMPLS_LVL | CMPLS_LVL | CLASS | DIP_SMD | FROM_PJ     | DATA                  | FP_ECN | EE_CHECK_LIST | CREATOR | CREATEDAY  | PSL | STATUS | ESD_CDM | ESD_HBM | ESD_MM | MSD  | PIN_LENGTH_LONG_PIN | PIN_LENGTH_SHORT_PIN ;
{========================================================================================}
 'SCONN56_1-2327679-3' | 'SMLF'    | 'IO'     | 'DFHS56FS022'(!) = ''       | ''               | 'DFHS56FS022' |'CON_F56S2H4D_P0-6W4-6_LUHXA'| 'CONN SMD HOUSING 56P 2R FS(P0.6, H9.25)' | 'TYC'   | '1-2327679-3' | 'EP(V1)'     | ''        | 'IO'  | ''      | 'S9NS-NICK' | 'TYC_1-2327679-3.pdf' | ''     | ''            | ''      | '20190104' | ''  | ''     | 'NA'    | 'NA'    | 'NA'   | 'NA' | '67 MILS'           | '56 MILS'           
 'SCONN56_1-2327679-3' | 'SMLF'    | 'EMPTY'  | 'DFHS56FS022'(!) = ''       | ''               | 'DFHS56FS022' |'CON_F56S2H4D_P0-6W4-6_LUHXA'| 'CONN SMD HOUSING 56P 2R FS(P0.6, H9.25)' | 'TYC'   | '1-2327679-3' | 'EP(V1)'     | ''        | 'IO'  | ''      | 'S9NS-NICK' | 'TYC_1-2327679-3.pdf' | ''     | ''            | ''      | '20190104' | ''  | ''     | 'NA'    | 'NA'    | 'NA'   | 'NA' | '67 MILS'           | '56 MILS'           

END_PART

END.

